FILE_TYPE = CONNECTIVITY;
{Allegro Design Entry HDL 17.2-2016 S081 (4005846) 1/11/2022}
"PAGE_NUMBER" = 212;
0"NC";
1"P3V3\g";
2"GND\g";
3"GND\g";
4"RST_PERST_SWB_N"CDS_PHYS_NET_NAME"RST_PCIE_RISER2_N";
5"RST_PCIE_CPU1_DEV_PERST_N"CDS_PHYS_NET_NAME"RST_PLTRST_N";
6"RST_PERST_SWB_R_N"CDS_PHYS_NET_NAME"RST_PCIE_RISER2_N";
7"FM_DB2000_OE_N";
8"RST_OCP_V3_2_N"CDS_PHYS_NET_NAME"RST_PCIE_EDSFF3_PERST_N";
9"FM_PLD_CLKS_OE_R_N";
10"FM_THERMTRIP_DLY_LVC1_N"CDS_PHYS_NET_NAME"FM_SLPS3_GF_N";
11"RST_PLTRST_PLD_B_N"CDS_PHYS_NET_NAME"RST_PLTRST_N";
12"FM_BMC_PWRBTN_OUT_N"CDS_PHYS_NET_NAME"FM_PCH_SLP_S3_N";
13"FM_SLPS3_PLD_N"CDS_PHYS_NET_NAME"FM_SLPS3_GF_N";
14"FM_THERMTRIP_DLY_LVC1_R_N"CDS_PHYS_NET_NAME"FM_PCH_SLP_S3_N";
15"FM_PLD_CLKS_DEV_EN";
16"FM_PLD_CLKS_DEV_R_EN";
17"FM_PLD_CLKS_DEV_EN"CDS_PHYS_NET_NAME"FM_SLPS3_GF_N";
18"RST_MB_STBY_N"CDS_PHYS_NET_NAME"FM_SLPS3_GF_N";
19"RST_RSMRST_PCH_N"CDS_PHYS_NET_NAME"FM_SLPS3_GF_N";
20"RST_RSMRST_NM_HDR_N"CDS_PHYS_NET_NAME"RST_PLTRST_PLD_N";
21"RST_MB_STBY_R_N"CDS_PHYS_NET_NAME"FM_PCH_SLP_S3_N";
22"RST_PLTRST_N"CDS_PHYS_NET_NAME"FM_PCH_SLP_S3_N";
23"RST_PCIE_CPU0_DEV_PERST_N"CDS_PHYS_NET_NAME"RST_PLTRST_N";
24"RST_OCP_V3_1_N"CDS_PHYS_NET_NAME"RST_OCP_V3_1_N";
25"RST_PLTRST_B_MUX_N"CDS_PHYS_NET_NAME"RST_PLTRST_PLD_N";
26"RST_PLTRST_B_N"CDS_PHYS_NET_NAME"RST_PLTRST_PLD_N";
27"RST_RSMRST_PLD_R_N"CDS_PHYS_NET_NAME"FM_PCH_SLP_S3_N";
28"FM_PCH_SLP_S3_N"CDS_PHYS_NET_NAME"FM_PCH_SLP_S3_N";
29"FM_ADR_MODE1"CDS_PHYS_NET_NAME"FM_PCH_SLP_S3_N";
30"FM_ADR_MODE1_R"CDS_PHYS_NET_NAME"FM_SLPS3_GF_N";
31"FM_PCH_SLP_S4_N"CDS_PHYS_NET_NAME"FM_PCH_SLP_S3_N";
32"FM_SLPS4_PLD_N"CDS_PHYS_NET_NAME"FM_SLPS3_GF_N";
33"RST_PLTRST_PLD_N"CDS_PHYS_NET_NAME"FM_SLPS3_GF_N";
34"FM_PLD_CLK_25M_R_EN"CDS_PHYS_NET_NAME"FM_PCH_SLP_S3_N";
35"FM_PLD_CLK_25M_EN"CDS_PHYS_NET_NAME"FM_SLPS3_GF_N";
36"FM_BMC_PWRBTN_N";
%"Q_RES"
"1","(-2800,2500)","0","pure_quanta","I10";
;
PART_NUMBER"CS03322FB03"
MATERIAL"CHIP"
WATTAGE"1/16W"
PACK_TYPE"0402LF"
TOLERANCE"1%"
VALUE"33.2"
$LOCATION"R1206"
CDS_LIB"pure_quanta"
CDS_LOCATION"R1206"
$SEC"1"
CDS_SEC"1";
"B"
$PN"2"18;
"A"
$PN"1"21;
%"Q_RES"
"1","(1900,2875)","0","pure_quanta","I105";
;
PART_NUMBER"CS03322FB03"
WATTAGE"1/16W"
VALUE"33.2"
TOLERANCE"1%"
PACK_TYPE"0402LF"
MATERIAL"CHIP"
$LOCATION"R1514"
CDS_LIB"pure_quanta"
CDS_LOCATION"R1514"
$SEC"1"
CDS_SEC"1";
"B"
$PN"2"24;
"A"
$PN"1"23;
%"Q_RES"
"1","(1900,925)","0","pure_quanta","I113";
;
PART_NUMBER"CS03322FB03"
WATTAGE"1/16W"
MATERIAL"CHIP"
TOLERANCE"1%"
VALUE"33.2"
PACK_TYPE"0402LF"
$LOCATION"R1520"
CDS_LIB"pure_quanta"
CDS_LOCATION"R1520"
$SEC"1"
CDS_SEC"1";
"B"
$PN"2"8;
"A"
$PN"1"5;
%"Q_RES"
"1","(1900,300)","0","pure_quanta","I127";
;
PART_NUMBER"CS03322FB03"
VALUE"33.2"
TOLERANCE"1%"
MATERIAL"CHIP"
WATTAGE"1/16W"
PACK_TYPE"0402LF"
$LOCATION"R2738"
CDS_LIB"pure_quanta"
CDS_LOCATION"R2738"
$SEC"1"
CDS_SEC"1";
"B"
$PN"2"6;
"A"
$PN"1"4;
%"Q_RES"
"1","(-2800,2075)","0","pure_quanta","I129";
;
PART_NUMBER"CS03322FB03"
TOLERANCE"1%"
VALUE"33.2"
MATERIAL"CHIP"
PACK_TYPE"0402LF"
WATTAGE"1/16W"
$LOCATION"R3050"
CDS_LIB"pure_quanta"
CDS_LOCATION"R3050"
$SEC"1"
CDS_SEC"1";
"B"
$PN"2"20;
"A"
$PN"1"27;
%"Q_RES"
"1","(1925,3775)","0","pure_quanta","I130";
;
PART_NUMBER"CS00002JB13"
VALUE"0"
WATTAGE"1/16W"
PACK_TYPE"0402LF"
TOLERANCE"5%"
MATERIAL"CHIP"
LOCATION"R1318"
CDS_LIB"pure_quanta"
$SEC"1"
CDS_SEC"1";
"B"
$PN"2"10;
"A"
$PN"1"14;
%"Q_RES"
"1","(-2800,2275)","0","pure_quanta","I15";
;
PART_NUMBER"CS03322FB03"
TOLERANCE"1%"
VALUE"33.2"
PACK_TYPE"0402LF"
MATERIAL"CHIP"
WATTAGE"1/16W"
$LOCATION"R1207"
CDS_LIB"pure_quanta"
CDS_LOCATION"R1207"
$SEC"1"
CDS_SEC"1";
"B"
$PN"2"19;
"A"
$PN"1"27;
%"Q_RES"
"1","(-2800,1575)","0","pure_quanta","I17";
;
PART_NUMBER"CS03322FB03"
MATERIAL"CHIP"
TOLERANCE"1%"
VALUE"33.2"
PACK_TYPE"0402LF"
WATTAGE"1/16W"
$LOCATION"R110"
CDS_LIB"pure_quanta"
CDS_LOCATION"R110"
$SEC"1"
CDS_SEC"1";
"B"
$PN"2"17;
"A"
$PN"1"16;
%"MOSFET_N"
"1","(-2800,675)","0","pure_quanta","I19";
;
PART_NUMBER"BAM138K0000"
VALUE"BSS138K"
MATERIAL"IC"
$LOCATION"U70"
MANUF_PN"BSS138K"
PACK_TYPE"SMLF"
CDS_LMAN_SYM_OUTLINE"-50,50,100,-150"
CDS_LIB"pure_quanta"
CDS_LOCATION"U70"
$SEC"1"
CDS_SEC"1";
"GATE"
$PN"G"15;
"SOURCE"
$PN"S"2;
"DRAIN"
$PN"D"9;
%"Q_RES"
"2","(-2750,1075)","0","pure_quanta","I24";
;
PART_NUMBER"CS31002FB08"
PACK_TYPE"0402LF"
TOLERANCE"1%"
VALUE"10K"
WATTAGE"1/16W"
MATERIAL"CHIP"
$LOCATION"R111"
CDS_LIB"pure_quanta"
CDS_LOCATION"R111"
$SEC"1"
CDS_SEC"1";
"A"
$PN"1"1;
"B"
$PN"2"9;
%"UNIVERSAL_POWER"
"1","(-2750,1275)","0","logical_power","I25";
;
HDL_POWER"P3V3"
CDS_LIB"logical_power";
"A"1;
%"UNIVERSAL_GND"
"1","(-2750,275)","0","logical_power","I26";
;
HDL_POWER"GND"
CDS_LIB"logical_power";
"A"2;
%"Q_RES"
"1","(-1550,825)","0","pure_quanta","I27";
;
PART_NUMBER"CS03322FB03"
TOLERANCE"1%"
VALUE"33.2"
PACK_TYPE"0402LF"
MATERIAL"CHIP"
WATTAGE"1/16W"
$LOCATION"R113"
CDS_LIB"pure_quanta"
CDS_LOCATION"R113"
$SEC"1"
CDS_SEC"1";
"B"
$PN"2"7;
"A"
$PN"1"9;
%"Q_RES"
"1","(-2800,3550)","0","pure_quanta","I44";
;
PART_NUMBER"CS03322FB03"
MATERIAL"CHIP"
TOLERANCE"1%"
VALUE"33.2"
WATTAGE"1/16W"
PACK_TYPE"0402LF"
$LOCATION"R109"
CDS_LIB"pure_quanta"
CDS_LOCATION"R109"
$SEC"1"
CDS_SEC"1";
"B"
$PN"2"35;
"A"
$PN"1"34;
%"Q_RES"
"1","(1925,3575)","0","pure_quanta","I55";
;
PART_NUMBER"CS03322FB03"
PACK_TYPE"0402LF"
VALUE"33.2"
TOLERANCE"1%"
MATERIAL"CHIP"
WATTAGE"1/16W"
$LOCATION"R1469"
CDS_LIB"pure_quanta"
CDS_LOCATION"R1469"
$SEC"1"
CDS_SEC"1";
"B"
$PN"2"26;
"A"
$PN"1"11;
%"Q_RES"
"1","(1925,3375)","0","pure_quanta","I56";
;
PART_NUMBER"CS03322FB03"
VALUE"33.2"
PACK_TYPE"0402LF"
TOLERANCE"1%"
WATTAGE"1/16W"
MATERIAL"CHIP"
$LOCATION"R1470"
CDS_LIB"pure_quanta"
CDS_LOCATION"R1470"
$SEC"1"
CDS_SEC"1";
"B"
$PN"2"25;
"A"
$PN"1"11;
%"Q_RES"
"1","(-2800,2925)","0","pure_quanta","I7";
;
PART_NUMBER"CS03322FB03"
TOLERANCE"1%"
VALUE"33.2"
WATTAGE"1/16W"
MATERIAL"CHIP"
PACK_TYPE"0402LF"
$LOCATION"R1205"
CDS_LIB"pure_quanta"
CDS_LOCATION"R1205"
$SEC"1"
CDS_SEC"1";
"B"
$PN"2"33;
"A"
$PN"1"22;
%"Q_RES"
"1","(-2800,3350)","0","pure_quanta","I86";
;
PART_NUMBER"CS03322FB03"
TOLERANCE"1%"
VALUE"33.2"
WATTAGE"1/16W"
MATERIAL"CHIP"
PACK_TYPE"0402LF"
$LOCATION"R1995"
CDS_LIB"pure_quanta"
CDS_LOCATION"R1995"
$SEC"1"
CDS_SEC"1";
"B"
$PN"2"13;
"A"
$PN"1"28;
%"Q_RES"
"1","(-2800,3150)","0","pure_quanta","I87";
;
PART_NUMBER"CS03322FB03"
TOLERANCE"1%"
VALUE"33.2"
WATTAGE"1/16W"
PACK_TYPE"0402LF"
MATERIAL"CHIP"
$LOCATION"R1996"
CDS_LIB"pure_quanta"
CDS_LOCATION"R1996"
$SEC"1"
CDS_SEC"1";
"B"
$PN"2"32;
"A"
$PN"1"31;
%"Q_RES"
"1","(1875,-550)","0","pure_quanta","I91";
;
PART_NUMBER"CS03322FB03"
WATTAGE"1/16W"
PACK_TYPE"0402LF"
TOLERANCE"1%"
VALUE"33.2"
MATERIAL"CHIP"
$LOCATION"R269"
CDS_LIB"pure_quanta"
CDS_LOCATION"R269"
$SEC"1"
CDS_SEC"1";
"B"
$PN"2"30;
"A"
$PN"1"29;
%"Q_RES"
"1","(-3775,2750)","0","pure_quanta","I92";
;
PART_NUMBER"CS41002FB09"
MATERIAL"CHIP"
VALUE"100K"
TOLERANCE"1%"
PACK_TYPE"0402LF"
WATTAGE"1/16W"
$LOCATION"R1541"
CDS_LIB"pure_quanta"
CDS_LOCATION"R1541"
$SEC"1"
CDS_SEC"1";
"B"
$PN"2"22;
"A"
$PN"1"3;
%"UNIVERSAL_GND"
"1","(-4150,2650)","0","logical_power","I93";
;
CDS_LIB"logical_power"
HDL_POWER"GND";
"A"3;
%"Q_RES"
"1","(-2800,3775)","0","pure_quanta","I94";
;
PART_NUMBER"CS00002JB13"
TOLERANCE"5%"
VALUE"0"
WATTAGE"1/16W"
MATERIAL"CHIP"
PACK_TYPE"0402LF"
$LOCATION"R1744"
CDS_LIB"pure_quanta"
CDS_LOCATION"R1744"
$SEC"1"
CDS_SEC"1";
"B"
$PN"2"36;
"A"
$PN"1"12;
END.
